(kicad_pcb
	(version 20260206)
	(generator "pcbnew")
	(generator_version "10.0")
	(general
		(thickness 1.6)
		(legacy_teardrops no)
	)
	(paper "A4")
	(title_block
		(title "03242023_DA0F0TMBIJ0_F0T_Motherboard_J_brd_V01_OCP.brd")
		(comment 1 "Grand Teton / footprints 741-746 of 6105")
	)
	(layers
		(0 "F.Cu" signal "TOP")
		(4 "In1.Cu" signal "GND")
		(6 "In2.Cu" signal "IN1")
		(8 "In3.Cu" signal "GND1")
		(10 "In4.Cu" signal "IN2")
		(12 "In5.Cu" signal "GND2")
		(14 "In6.Cu" signal "IN3")
		(16 "In7.Cu" signal "GND3")
		(18 "In8.Cu" signal "VCC")
		(20 "In9.Cu" signal "VCC1")
		(22 "In10.Cu" signal "GND4")
		(24 "In11.Cu" signal "IN4")
		(26 "In12.Cu" signal "GND5")
		(28 "In13.Cu" signal "IN5")
		(30 "In14.Cu" signal "GND6")
		(32 "In15.Cu" signal "IN6")
		(34 "In16.Cu" signal "GND7")
		(2 "B.Cu" signal "BOTTOM")
		(9 "F.Adhes" user "F.Adhesive")
		(11 "B.Adhes" user "B.Adhesive")
		(13 "F.Paste" user "Package Geometry/Pastemask Top")
		(15 "B.Paste" user "Package Geometry/Pastemask Bottom")
		(5 "F.SilkS" user "Ref Des/Silkscreen Top")
		(7 "B.SilkS" user "Ref Des/Silkscreen Bottom")
		(1 "F.Mask" user "Board Geometry/Soldermask Top")
		(3 "B.Mask" user "Board Geometry/Soldermask Bottom")
		(17 "Dwgs.User" user "User.Drawings")
		(19 "Cmts.User" user "User.Comments")
		(21 "Eco1.User" user "User.Eco1")
		(23 "Eco2.User" user "User.Eco2")
		(25 "Edge.Cuts" user "Board Geometry/Outline")
		(27 "Margin" user)
		(31 "F.CrtYd" user "Package Geometry/Place Bound Top")
		(29 "B.CrtYd" user "Package Geometry/Place Bound Bottom")
		(35 "F.Fab" user "Ref Des/Assembly Top")
		(33 "B.Fab" user "Ref Des/Assembly Bottom")
	)
	(footprint ""
		(layer "F.Cu")
		(at 113.494312 -133.472682 180)
		(property "Reference" "R3394"
			(at 0 0 180)
			(layer "F.SilkS")
			(hide yes)
			(effects
				(font
					(size 1.27 1.27)
				)
			)
		)
		(property "Value" ""
			(at 0 0 180)
			(layer "F.Fab")
			(effects
				(font
					(size 1.27 1.27)
				)
			)
		)
		(duplicate_pad_numbers_are_jumpers no)
		(fp_line
			(start 0.7874 0.4064)
			(end -0.7874 0.4064)
			(stroke
				(width 0.1524)
				(type default)
			)
			(layer "F.SilkS")
		)
		(fp_line
			(start 0.7874 -0.4064)
			(end 0.7874 0.4064)
			(stroke
				(width 0.1524)
				(type default)
			)
			(layer "F.SilkS")
		)
		(fp_line
			(start -0.7874 0.4064)
			(end -0.7874 -0.4064)
			(stroke
				(width 0.1524)
				(type default)
			)
			(layer "F.SilkS")
		)
		(fp_line
			(start -0.7874 -0.4064)
			(end 0.7874 -0.4064)
			(stroke
				(width 0.1524)
				(type default)
			)
			(layer "F.SilkS")
		)
		(fp_line
			(start 0.67945 0.3048)
			(end 0.120396 0.3048)
			(stroke
				(width 0.1)
				(type default)
			)
			(layer "F.Fab")
		)
		(fp_line
			(start 0.67945 -0.3048)
			(end 0.67945 0.3048)
			(stroke
				(width 0.1)
				(type default)
			)
			(layer "F.Fab")
		)
		(fp_line
			(start 0.12065 -0.2794)
			(end 0.12065 -0.3048)
			(stroke
				(width 0.1)
				(type default)
			)
			(layer "F.Fab")
		)
		(fp_line
			(start 0.12065 -0.3048)
			(end 0.67945 -0.3048)
			(stroke
				(width 0.1)
				(type default)
			)
			(layer "F.Fab")
		)
		(fp_line
			(start 0.120396 0.3048)
			(end 0.120396 0.2794)
			(stroke
				(width 0.1)
				(type default)
			)
			(layer "F.Fab")
		)
		(fp_line
			(start 0.120396 0.2794)
			(end -0.12065 0.2794)
			(stroke
				(width 0.1)
				(type default)
			)
			(layer "F.Fab")
		)
		(fp_line
			(start -0.12065 0.3048)
			(end -0.67945 0.3048)
			(stroke
				(width 0.1)
				(type default)
			)
			(layer "F.Fab")
		)
		(fp_line
			(start -0.12065 0.2794)
			(end -0.12065 0.3048)
			(stroke
				(width 0.1)
				(type default)
			)
			(layer "F.Fab")
		)
		(fp_line
			(start -0.12065 -0.2794)
			(end 0.12065 -0.2794)
			(stroke
				(width 0.1)
				(type default)
			)
			(layer "F.Fab")
		)
		(fp_line
			(start -0.12065 -0.305054)
			(end -0.12065 -0.2794)
			(stroke
				(width 0.1)
				(type default)
			)
			(layer "F.Fab")
		)
		(fp_line
			(start -0.67945 0.3048)
			(end -0.67945 -0.305054)
			(stroke
				(width 0.1)
				(type default)
			)
			(layer "F.Fab")
		)
		(fp_line
			(start -0.67945 -0.305054)
			(end -0.12065 -0.305054)
			(stroke
				(width 0.1)
				(type default)
			)
			(layer "F.Fab")
		)
		(pad "1" smd circle
			(at -0.40005 0 180)
			(size 0 0)
			(layers "F.Cu" "F.Mask" "F.Paste")
			(net "SMB_IOEXP_3V3AUX_SDA_R")
		)
		(pad "2" smd circle
			(at 0.40005 0 180)
			(size 0 0)
			(layers "F.Cu" "F.Mask" "F.Paste")
			(net "SMB_IOEXP_3V3AUX_SDA")
		)
	)
	(footprint ""
		(layer "F.Cu")
		(at 143.3322 -104.116378 -90)
		(property "Reference" "R346"
			(at 0 0 270)
			(layer "F.SilkS")
			(hide yes)
			(effects
				(font
					(size 1.27 1.27)
				)
			)
		)
		(property "Value" ""
			(at 0 0 270)
			(layer "F.Fab")
			(effects
				(font
					(size 1.27 1.27)
				)
			)
		)
		(duplicate_pad_numbers_are_jumpers no)
		(fp_line
			(start -0.7874 0.4064)
			(end -0.7874 -0.4064)
			(stroke
				(width 0.1524)
				(type default)
			)
			(layer "F.SilkS")
		)
		(fp_line
			(start 0.7874 0.4064)
			(end -0.7874 0.4064)
			(stroke
				(width 0.1524)
				(type default)
			)
			(layer "F.SilkS")
		)
		(fp_line
			(start -0.7874 -0.4064)
			(end 0.7874 -0.4064)
			(stroke
				(width 0.1524)
				(type default)
			)
			(layer "F.SilkS")
		)
		(fp_line
			(start 0.7874 -0.4064)
			(end 0.7874 0.4064)
			(stroke
				(width 0.1524)
				(type default)
			)
			(layer "F.SilkS")
		)
		(fp_line
			(start -0.67945 0.3048)
			(end -0.67945 -0.305054)
			(stroke
				(width 0.1)
				(type default)
			)
			(layer "F.Fab")
		)
		(fp_line
			(start -0.12065 0.3048)
			(end -0.67945 0.3048)
			(stroke
				(width 0.1)
				(type default)
			)
			(layer "F.Fab")
		)
		(fp_line
			(start 0.120396 0.3048)
			(end 0.120396 0.2794)
			(stroke
				(width 0.1)
				(type default)
			)
			(layer "F.Fab")
		)
		(fp_line
			(start 0.67945 0.3048)
			(end 0.120396 0.3048)
			(stroke
				(width 0.1)
				(type default)
			)
			(layer "F.Fab")
		)
		(fp_line
			(start -0.12065 0.2794)
			(end -0.12065 0.3048)
			(stroke
				(width 0.1)
				(type default)
			)
			(layer "F.Fab")
		)
		(fp_line
			(start 0.120396 0.2794)
			(end -0.12065 0.2794)
			(stroke
				(width 0.1)
				(type default)
			)
			(layer "F.Fab")
		)
		(fp_line
			(start -0.12065 -0.2794)
			(end 0.12065 -0.2794)
			(stroke
				(width 0.1)
				(type default)
			)
			(layer "F.Fab")
		)
		(fp_line
			(start 0.12065 -0.2794)
			(end 0.12065 -0.3048)
			(stroke
				(width 0.1)
				(type default)
			)
			(layer "F.Fab")
		)
		(fp_line
			(start 0.12065 -0.3048)
			(end 0.67945 -0.3048)
			(stroke
				(width 0.1)
				(type default)
			)
			(layer "F.Fab")
		)
		(fp_line
			(start 0.67945 -0.3048)
			(end 0.67945 0.3048)
			(stroke
				(width 0.1)
				(type default)
			)
			(layer "F.Fab")
		)
		(fp_line
			(start -0.67945 -0.305054)
			(end -0.12065 -0.305054)
			(stroke
				(width 0.1)
				(type default)
			)
			(layer "F.Fab")
		)
		(fp_line
			(start -0.12065 -0.305054)
			(end -0.12065 -0.2794)
			(stroke
				(width 0.1)
				(type default)
			)
			(layer "F.Fab")
		)
		(pad "1" smd circle
			(at -0.40005 0 270)
			(size 0 0)
			(layers "F.Cu" "F.Mask" "F.Paste")
			(net "H_CPU_ERR2_LVC1_R_N")
		)
		(pad "2" smd circle
			(at 0.40005 0 270)
			(size 0 0)
			(layers "F.Cu" "F.Mask" "F.Paste")
			(net "H_CPU_ERR2_LVC1_N")
		)
	)
	(footprint ""
		(layer "F.Cu")
		(at 80.981296 -70.78599)
		(property "Reference" "D65"
			(at -41.742106 50.178462 90)
			(unlocked yes)
			(layer "F.SilkS")
			(effects
				(font
					(size 0.635 0.4064)
					(thickness 0.1524)
				)
				(justify left)
			)
		)
		(property "Value" ""
			(at 0 0 0)
			(layer "F.Fab")
			(effects
				(font
					(size 1.27 1.27)
				)
			)
		)
		(duplicate_pad_numbers_are_jumpers no)
		(fp_line
			(start -0.90678 0.4826)
			(end -0.90678 -0.4699)
			(stroke
				(width 0.1524)
				(type default)
			)
			(layer "F.SilkS")
		)
		(fp_line
			(start -0.89408 -0.4826)
			(end 0.90678 -0.4826)
			(stroke
				(width 0.1524)
				(type default)
			)
			(layer "F.SilkS")
		)
		(fp_line
			(start -0.79248 -0.4826)
			(end 1.03378 -0.4826)
			(stroke
				(width 0.1524)
				(type default)
			)
			(layer "F.SilkS")
		)
		(fp_line
			(start -0.64008 -0.4826)
			(end 1.16078 -0.4826)
			(stroke
				(width 0.1524)
				(type default)
			)
			(layer "F.SilkS")
		)
		(fp_line
			(start 0.90678 -0.4826)
			(end 0.90678 0.4826)
			(stroke
				(width 0.1524)
				(type default)
			)
			(layer "F.SilkS")
		)
		(fp_line
			(start 0.90678 0.4826)
			(end -0.90678 0.4826)
			(stroke
				(width 0.1524)
				(type default)
			)
			(layer "F.SilkS")
		)
		(fp_line
			(start 1.03378 -0.4826)
			(end 1.03378 0.4826)
			(stroke
				(width 0.1524)
				(type default)
			)
			(layer "F.SilkS")
		)
		(fp_line
			(start 1.03378 0.4826)
			(end -0.79248 0.4826)
			(stroke
				(width 0.1524)
				(type default)
			)
			(layer "F.SilkS")
		)
		(fp_line
			(start 1.16078 -0.4826)
			(end 1.16078 0.4826)
			(stroke
				(width 0.1524)
				(type default)
			)
			(layer "F.SilkS")
		)
		(fp_line
			(start 1.16078 0.4826)
			(end -0.64008 0.4826)
			(stroke
				(width 0.1524)
				(type default)
			)
			(layer "F.SilkS")
		)
		(fp_line
			(start -0.499872 -0.249936)
			(end 0.499872 -0.249936)
			(stroke
				(width 0.1)
				(type default)
			)
			(layer "F.Fab")
		)
		(fp_line
			(start -0.499872 0.249936)
			(end -0.499872 -0.249936)
			(stroke
				(width 0.1)
				(type default)
			)
			(layer "F.Fab")
		)
		(fp_line
			(start 0.499872 -0.249936)
			(end 0.499872 0.249936)
			(stroke
				(width 0.1)
				(type default)
			)
			(layer "F.Fab")
		)
		(fp_line
			(start 0.499872 0.249936)
			(end -0.499872 0.249936)
			(stroke
				(width 0.1)
				(type default)
			)
			(layer "F.Fab")
		)
		(pad "A" smd rect
			(at -0.47498 0)
			(size 0.6096 0.7112)
			(layers "F.Cu" "F.Mask" "F.Paste")
			(net "LED_RST_PLD_CPU0_DRAM_AB_N")
		)
		(pad "C" smd rect
			(at 0.47498 0)
			(size 0.6096 0.7112)
			(layers "F.Cu" "F.Mask" "F.Paste")
			(net "LED_RST_PLD_CPU0_DRAM_AB_N_D")
		)
	)
	(footprint ""
		(layer "F.Cu")
		(at 280.786078 -424.5483 90)
		(property "Reference" "R4670"
			(at 0 0 90)
			(layer "F.SilkS")
			(hide yes)
			(effects
				(font
					(size 1.27 1.27)
				)
			)
		)
		(property "Value" ""
			(at 0 0 90)
			(layer "F.Fab")
			(effects
				(font
					(size 1.27 1.27)
				)
			)
		)
		(duplicate_pad_numbers_are_jumpers no)
		(fp_line
			(start 0.7874 -0.4064)
			(end 0.7874 0.4064)
			(stroke
				(width 0.1524)
				(type default)
			)
			(layer "F.SilkS")
		)
		(fp_line
			(start -0.7874 -0.4064)
			(end 0.7874 -0.4064)
			(stroke
				(width 0.1524)
				(type default)
			)
			(layer "F.SilkS")
		)
		(fp_line
			(start 0.7874 0.4064)
			(end -0.7874 0.4064)
			(stroke
				(width 0.1524)
				(type default)
			)
			(layer "F.SilkS")
		)
		(fp_line
			(start -0.7874 0.4064)
			(end -0.7874 -0.4064)
			(stroke
				(width 0.1524)
				(type default)
			)
			(layer "F.SilkS")
		)
		(fp_line
			(start -0.12065 -0.305054)
			(end -0.12065 -0.2794)
			(stroke
				(width 0.1)
				(type default)
			)
			(layer "F.Fab")
		)
		(fp_line
			(start -0.67945 -0.305054)
			(end -0.12065 -0.305054)
			(stroke
				(width 0.1)
				(type default)
			)
			(layer "F.Fab")
		)
		(fp_line
			(start 0.67945 -0.3048)
			(end 0.67945 0.3048)
			(stroke
				(width 0.1)
				(type default)
			)
			(layer "F.Fab")
		)
		(fp_line
			(start 0.12065 -0.3048)
			(end 0.67945 -0.3048)
			(stroke
				(width 0.1)
				(type default)
			)
			(layer "F.Fab")
		)
		(fp_line
			(start 0.12065 -0.2794)
			(end 0.12065 -0.3048)
			(stroke
				(width 0.1)
				(type default)
			)
			(layer "F.Fab")
		)
		(fp_line
			(start -0.12065 -0.2794)
			(end 0.12065 -0.2794)
			(stroke
				(width 0.1)
				(type default)
			)
			(layer "F.Fab")
		)
		(fp_line
			(start 0.120396 0.2794)
			(end -0.12065 0.2794)
			(stroke
				(width 0.1)
				(type default)
			)
			(layer "F.Fab")
		)
		(fp_line
			(start -0.12065 0.2794)
			(end -0.12065 0.3048)
			(stroke
				(width 0.1)
				(type default)
			)
			(layer "F.Fab")
		)
		(fp_line
			(start 0.67945 0.3048)
			(end 0.120396 0.3048)
			(stroke
				(width 0.1)
				(type default)
			)
			(layer "F.Fab")
		)
		(fp_line
			(start 0.120396 0.3048)
			(end 0.120396 0.2794)
			(stroke
				(width 0.1)
				(type default)
			)
			(layer "F.Fab")
		)
		(fp_line
			(start -0.12065 0.3048)
			(end -0.67945 0.3048)
			(stroke
				(width 0.1)
				(type default)
			)
			(layer "F.Fab")
		)
		(fp_line
			(start -0.67945 0.3048)
			(end -0.67945 -0.305054)
			(stroke
				(width 0.1)
				(type default)
			)
			(layer "F.Fab")
		)
		(pad "1" smd circle
			(at -0.40005 0 90)
			(size 0 0)
			(layers "F.Cu" "F.Mask" "F.Paste")
			(net "A_HSC_HIGH")
		)
		(pad "2" smd circle
			(at 0.40005 0 90)
			(size 0 0)
			(layers "F.Cu" "F.Mask" "F.Paste")
			(net "GND")
		)
	)
	(footprint ""
		(layer "F.Cu")
		(at 84.44611 -59.242706 90)
		(property "Reference" "PR3824"
			(at 0 0 90)
			(layer "F.SilkS")
			(hide yes)
			(effects
				(font
					(size 1.27 1.27)
				)
			)
		)
		(property "Value" ""
			(at 0 0 90)
			(layer "F.Fab")
			(effects
				(font
					(size 1.27 1.27)
				)
			)
		)
		(duplicate_pad_numbers_are_jumpers no)
		(fp_line
			(start 0.7874 -0.4064)
			(end 0.7874 0.4064)
			(stroke
				(width 0.1524)
				(type default)
			)
			(layer "F.SilkS")
		)
		(fp_line
			(start -0.7874 -0.4064)
			(end 0.7874 -0.4064)
			(stroke
				(width 0.1524)
				(type default)
			)
			(layer "F.SilkS")
		)
		(fp_line
			(start 0.7874 0.4064)
			(end -0.7874 0.4064)
			(stroke
				(width 0.1524)
				(type default)
			)
			(layer "F.SilkS")
		)
		(fp_line
			(start -0.7874 0.4064)
			(end -0.7874 -0.4064)
			(stroke
				(width 0.1524)
				(type default)
			)
			(layer "F.SilkS")
		)
		(fp_line
			(start -0.12065 -0.305054)
			(end -0.12065 -0.2794)
			(stroke
				(width 0.1)
				(type default)
			)
			(layer "F.Fab")
		)
		(fp_line
			(start -0.67945 -0.305054)
			(end -0.12065 -0.305054)
			(stroke
				(width 0.1)
				(type default)
			)
			(layer "F.Fab")
		)
		(fp_line
			(start 0.67945 -0.3048)
			(end 0.67945 0.3048)
			(stroke
				(width 0.1)
				(type default)
			)
			(layer "F.Fab")
		)
		(fp_line
			(start 0.12065 -0.3048)
			(end 0.67945 -0.3048)
			(stroke
				(width 0.1)
				(type default)
			)
			(layer "F.Fab")
		)
		(fp_line
			(start 0.12065 -0.2794)
			(end 0.12065 -0.3048)
			(stroke
				(width 0.1)
				(type default)
			)
			(layer "F.Fab")
		)
		(fp_line
			(start -0.12065 -0.2794)
			(end 0.12065 -0.2794)
			(stroke
				(width 0.1)
				(type default)
			)
			(layer "F.Fab")
		)
		(fp_line
			(start 0.120396 0.2794)
			(end -0.12065 0.2794)
			(stroke
				(width 0.1)
				(type default)
			)
			(layer "F.Fab")
		)
		(fp_line
			(start -0.12065 0.2794)
			(end -0.12065 0.3048)
			(stroke
				(width 0.1)
				(type default)
			)
			(layer "F.Fab")
		)
		(fp_line
			(start 0.67945 0.3048)
			(end 0.120396 0.3048)
			(stroke
				(width 0.1)
				(type default)
			)
			(layer "F.Fab")
		)
		(fp_line
			(start 0.120396 0.3048)
			(end 0.120396 0.2794)
			(stroke
				(width 0.1)
				(type default)
			)
			(layer "F.Fab")
		)
		(fp_line
			(start -0.12065 0.3048)
			(end -0.67945 0.3048)
			(stroke
				(width 0.1)
				(type default)
			)
			(layer "F.Fab")
		)
		(fp_line
			(start -0.67945 0.3048)
			(end -0.67945 -0.305054)
			(stroke
				(width 0.1)
				(type default)
			)
			(layer "F.Fab")
		)
		(pad "1" smd circle
			(at -0.40005 0 90)
			(size 0 0)
			(layers "F.Cu" "F.Mask" "F.Paste")
			(net "P3V3_OCP_SENSE_2")
		)
		(pad "2" smd circle
			(at 0.40005 0 90)
			(size 0 0)
			(layers "F.Cu" "F.Mask" "F.Paste")
			(net "GND")
		)
	)
	(footprint ""
		(layer "F.Cu")
		(at 357.548942 -390.43737 180)
		(property "Reference" "R4163"
			(at 0 0 180)
			(layer "F.SilkS")
			(hide yes)
			(effects
				(font
					(size 1.27 1.27)
				)
			)
		)
		(property "Value" ""
			(at 0 0 180)
			(layer "F.Fab")
			(effects
				(font
					(size 1.27 1.27)
				)
			)
		)
		(duplicate_pad_numbers_are_jumpers no)
		(fp_line
			(start 0.7874 0.4064)
			(end -0.7874 0.4064)
			(stroke
				(width 0.1524)
				(type default)
			)
			(layer "F.SilkS")
		)
		(fp_line
			(start 0.7874 -0.4064)
			(end 0.7874 0.4064)
			(stroke
				(width 0.1524)
				(type default)
			)
			(layer "F.SilkS")
		)
		(fp_line
			(start -0.7874 0.4064)
			(end -0.7874 -0.4064)
			(stroke
				(width 0.1524)
				(type default)
			)
			(layer "F.SilkS")
		)
		(fp_line
			(start -0.7874 -0.4064)
			(end 0.7874 -0.4064)
			(stroke
				(width 0.1524)
				(type default)
			)
			(layer "F.SilkS")
		)
		(fp_line
			(start 0.67945 0.3048)
			(end 0.120396 0.3048)
			(stroke
				(width 0.1)
				(type default)
			)
			(layer "F.Fab")
		)
		(fp_line
			(start 0.67945 -0.3048)
			(end 0.67945 0.3048)
			(stroke
				(width 0.1)
				(type default)
			)
			(layer "F.Fab")
		)
		(fp_line
			(start 0.12065 -0.2794)
			(end 0.12065 -0.3048)
			(stroke
				(width 0.1)
				(type default)
			)
			(layer "F.Fab")
		)
		(fp_line
			(start 0.12065 -0.3048)
			(end 0.67945 -0.3048)
			(stroke
				(width 0.1)
				(type default)
			)
			(layer "F.Fab")
		)
		(fp_line
			(start 0.120396 0.3048)
			(end 0.120396 0.2794)
			(stroke
				(width 0.1)
				(type default)
			)
			(layer "F.Fab")
		)
		(fp_line
			(start 0.120396 0.2794)
			(end -0.12065 0.2794)
			(stroke
				(width 0.1)
				(type default)
			)
			(layer "F.Fab")
		)
		(fp_line
			(start -0.12065 0.3048)
			(end -0.67945 0.3048)
			(stroke
				(width 0.1)
				(type default)
			)
			(layer "F.Fab")
		)
		(fp_line
			(start -0.12065 0.2794)
			(end -0.12065 0.3048)
			(stroke
				(width 0.1)
				(type default)
			)
			(layer "F.Fab")
		)
		(fp_line
			(start -0.12065 -0.2794)
			(end 0.12065 -0.2794)
			(stroke
				(width 0.1)
				(type default)
			)
			(layer "F.Fab")
		)
		(fp_line
			(start -0.12065 -0.305054)
			(end -0.12065 -0.2794)
			(stroke
				(width 0.1)
				(type default)
			)
			(layer "F.Fab")
		)
		(fp_line
			(start -0.67945 0.3048)
			(end -0.67945 -0.305054)
			(stroke
				(width 0.1)
				(type default)
			)
			(layer "F.Fab")
		)
		(fp_line
			(start -0.67945 -0.305054)
			(end -0.12065 -0.305054)
			(stroke
				(width 0.1)
				(type default)
			)
			(layer "F.Fab")
		)
		(pad "1" smd circle
			(at -0.40005 0 180)
			(size 0 0)
			(layers "F.Cu" "F.Mask" "F.Paste")
			(net "GPU_3V3IO_RSVD3")
		)
		(pad "2" smd circle
			(at 0.40005 0 180)
			(size 0 0)
			(layers "F.Cu" "F.Mask" "F.Paste")
			(net "GND")
		)
	)
)
